# CM4 Baseboard — KiCad project settings (.kicad_pro: net classes, design rules, text variables)
{
  "board": {
    "3dviewports": [],
    "design_settings": {
      "defaults": {
        "apply_defaults_to_fp_fields": false,
        "apply_defaults_to_fp_shapes": false,
        "apply_defaults_to_fp_text": false,
        "board_outline_line_width": 0.1,
        "copper_line_width": 0.2,
        "copper_text_italic": false,
        "copper_text_size_h": 1.5,
        "copper_text_size_v": 1.5,
        "copper_text_thickness": 0.3,
        "copper_text_upright": false,
        "courtyard_line_width": 0.05,
        "dimension_precision": 4,
        "dimension_units": 3,
        "dimensions": {
          "arrow_length": 1270000,
          "extension_offset": 500000,
          "keep_text_aligned": true,
          "suppress_zeroes": false,
          "text_position": 0,
          "units_format": 1
        },
        "fab_line_width": 0.1,
        "fab_text_italic": false,
        "fab_text_size_h": 1.0,
        "fab_text_size_v": 1.0,
        "fab_text_thickness": 0.15,
        "fab_text_upright": false,
        "other_line_width": 0.1,
        "other_text_italic": false,
        "other_text_size_h": 1.0,
        "other_text_size_v": 1.0,
        "other_text_thickness": 0.15,
        "other_text_upright": false,
        "pads": {
          "drill": 0.0,
          "height": 0.75,
          "width": 0.75
        },
        "silk_line_width": 0.15,
        "silk_text_italic": false,
        "silk_text_size_h": 1.0,
        "silk_text_size_v": 1.0,
        "silk_text_thickness": 0.15,
        "silk_text_upright": false,
        "zones": {
          "45_degree_only": true,
          "min_clearance": 0.5
        }
      },
      "diff_pair_dimensions": [
        {
          "gap": 0.0,
          "via_gap": 0.0,
          "width": 0.0
        }
      ],
      "drc_exclusions": [],
      "meta": {
        "filename": "board_design_settings.json",
        "version": 2
      },
      "rule_severities": {
        "annular_width": "error",
        "clearance": "error",
        "connection_width": "warning",
        "copper_edge_clearance": "error",
        "copper_sliver": "warning",
        "courtyards_overlap": "error",
        "creepage": "error",
        "diff_pair_gap_out_of_range": "ignore",
        "diff_pair_uncoupled_length_too_long": "error",
        "drill_out_of_range": "error",
        "duplicate_footprints": "warning",
        "extra_footprint": "warning",
        "footprint": "error",
        "footprint_filters_mismatch": "ignore",
        "footprint_symbol_mismatch": "warning",
        "footprint_type_mismatch": "ignore",
        "hole_clearance": "error",
        "hole_near_hole": "error",
        "hole_to_hole": "error",
        "holes_co_located": "warning",
        "invalid_outline": "error",
        "isolated_copper": "warning",
        "item_on_disabled_layer": "error",
        "items_not_allowed": "error",
        "length_out_of_range": "error",
        "lib_footprint_issues": "warning",
        "lib_footprint_mismatch": "warning",
        "malformed_courtyard": "error",
        "microvia_drill_out_of_range": "error",
        "mirrored_text_on_front_layer": "warning",
        "missing_courtyard": "warning",
        "missing_footprint": "warning",
        "net_conflict": "warning",
        "nonmirrored_text_on_back_layer": "warning",
        "npth_inside_courtyard": "warning",
        "padstack": "error",
        "pth_inside_courtyard": "warning",
        "shorting_items": "error",
        "silk_edge_clearance": "warning",
        "silk_over_copper": "warning",
        "silk_overlap": "warning",
        "skew_out_of_range": "error",
        "solder_mask_bridge": "error",
        "starved_thermal": "error",
        "text_height": "warning",
        "text_on_edge_cuts": "error",
        "text_thickness": "warning",
        "through_hole_pad_without_hole": "error",
        "too_many_vias": "error",
        "track_angle": "error",
        "track_dangling": "warning",
        "track_segment_length": "error",
        "track_width": "error",
        "tracks_crossing": "error",
        "unconnected_items": "error",
        "unresolved_variable": "error",
        "via_dangling": "warning",
        "zones_intersect": "error"
      },
      "rule_severitieslegacy_courtyards_overlap": true,
      "rule_severitieslegacy_no_courtyard_defined": false,
      "rules": {
        "allow_blind_buried_vias": false,
        "allow_microvias": false,
        "max_error": 0.0025,
        "min_clearance": 0.125,
        "min_connection": 0.125,
        "min_copper_edge_clearance": 0.2,
        "min_groove_width": 0.0,
        "min_hole_clearance": 0.15,
        "min_hole_to_hole": 0.25,
        "min_microvia_diameter": 0.2,
        "min_microvia_drill": 0.1,
        "min_resolved_spokes": 1,
        "min_silk_clearance": 0.0,
        "min_text_height": 0.7,
        "min_text_thickness": 0.065,
        "min_through_hole_diameter": 0.1,
        "min_track_width": 0.125,
        "min_via_annular_width": 0.125,
        "min_via_diameter": 0.45,
        "solder_mask_to_copper_clearance": 0.0,
        "use_height_for_length_calcs": true
      },
      "teardrop_options": [
        {
          "td_onpthpad": true,
          "td_onroundshapesonly": false,
          "td_onsmdpad": true,
          "td_ontrackend": false,
          "td_onvia": true
        }
      ],
      "teardrop_parameters": [
        {
          "td_allow_use_two_tracks": true,
          "td_curve_segcount": 0,
          "td_height_ratio": 1.0,
          "td_length_ratio": 0.5,
          "td_maxheight": 2.0,
          "td_maxlen": 1.0,
          "td_on_pad_in_zone": false,
          "td_target_name": "td_round_shape",
          "td_width_to_size_filter_ratio": 0.9
        },
        {
          "td_allow_use_two_tracks": true,
          "td_curve_segcount": 0,
          "td_height_ratio": 1.0,
          "td_length_ratio": 0.5,
          "td_maxheight": 2.0,
          "td_maxlen": 1.0,
          "td_on_pad_in_zone": false,
          "td_target_name": "td_rect_shape",
          "td_width_to_size_filter_ratio": 0.9
        },
        {
          "td_allow_use_two_tracks": true,
          "td_curve_segcount": 0,
          "td_height_ratio": 1.0,
          "td_length_ratio": 0.5,
          "td_maxheight": 2.0,
          "td_maxlen": 1.0,
          "td_on_pad_in_zone": false,
          "td_target_name": "td_track_end",
          "td_width_to_size_filter_ratio": 0.9
        }
      ],
      "track_widths": [
        0.0,
        0.127,
        0.15,
        0.18,
        0.2,
        0.254,
        0.35,
        0.4,
        0.5,
        0.6,
        0.75,
        1.0,
        1.25,
        1.5,
        1.75,
        2.0
      ],
      "tuning_pattern_settings": {
        "diff_pair_defaults": {
          "corner_radius_percentage": 80,
          "corner_style": 1,
          "max_amplitude": 1.0,
          "min_amplitude": 0.2,
          "single_sided": false,
          "spacing": 1.0
        },
        "diff_pair_skew_defaults": {
          "corner_radius_percentage": 80,
          "corner_style": 1,
          "max_amplitude": 1.0,
          "min_amplitude": 0.2,
          "single_sided": false,
          "spacing": 0.6
        },
        "single_track_defaults": {
          "corner_radius_percentage": 80,
          "corner_style": 1,
          "max_amplitude": 1.0,
          "min_amplitude": 0.2,
          "single_sided": false,
          "spacing": 0.6
        }
      },
      "via_dimensions": [
        {
          "diameter": 0.0,
          "drill": 0.0
        },
        {
          "diameter": 0.45,
          "drill": 0.1
        },
        {
          "diameter": 0.45,
          "drill": 0.15
        },
        {
          "diameter": 0.5,
          "drill": 0.15
        },
        {
          "diameter": 0.5,
          "drill": 0.15
        },
        {
          "diameter": 0.5,
          "drill": 0.15
        },
        {
          "diameter": 0.5,
          "drill": 0.2
        },
        {
          "diameter": 0.65,
          "drill": 0.35
        }
      ],
      "zones_allow_external_fillets": true,
      "zones_use_no_outline": true
    },
    "ipc2581": {
      "dist": "",
      "distpn": "",
      "internal_id": "",
      "mfg": "",
      "mpn": ""
    },
    "layer_pairs": [],
    "layer_presets": [],
    "viewports": []
  },
  "boards": [],
  "cvpcb": {
    "equivalence_files": []
  },
  "erc": {
    "erc_exclusions": [],
    "meta": {
      "version": 0
    },
    "pin_map": [
      [
        0,
        0,
        0,
        0,
        0,
        0,
        1,
        0,
        0,
        0,
        0,
        2
      ],
      [
        0,
        2,
        0,
        1,
        0,
        0,
        1,
        0,
        2,
        2,
        2,
        2
      ],
      [
        0,
        0,
        0,
        0,
        0,
        0,
        1,
        0,
        1,
        0,
        1,
        2
      ],
      [
        0,
        1,
        0,
        0,
        0,
        0,
        1,
        0,
        2,
        1,
        1,
        2
      ],
      [
        0,
        0,
        0,
        0,
        0,
        0,
        1,
        0,
        0,
        0,
        0,
        2
      ],
      [
        0,
        0,
        0,
        0,
        0,
        0,
        0,
        0,
        0,
        0,
        0,
        2
      ],
      [
        1,
        1,
        1,
        1,
        1,
        0,
        1,
        1,
        1,
        1,
        1,
        2
      ],
      [
        0,
        0,
        0,
        0,
        0,
        0,
        1,
        0,
        0,
        0,
        0,
        2
      ],
      [
        0,
        2,
        1,
        2,
        0,
        0,
        1,
        0,
        2,
        2,
        2,
        2
      ],
      [
        0,
        2,
        0,
        1,
        0,
        0,
        1,
        0,
        2,
        0,
        0,
        2
      ],
      [
        0,
        2,
        1,
        1,
        0,
        0,
        1,
        0,
        2,
        0,
        0,
        2
      ],
      [
        2,
        2,
        2,
        2,
        2,
        2,
        2,
        2,
        2,
        2,
        2,
        2
      ]
    ],
    "rule_severities": {
      "bus_definition_conflict": "error",
      "bus_entry_needed": "error",
      "bus_to_bus_conflict": "error",
      "bus_to_net_conflict": "error",
      "conflicting_netclasses": "error",
      "different_unit_footprint": "error",
      "different_unit_net": "error",
      "duplicate_reference": "error",
      "duplicate_sheet_names": "error",
      "endpoint_off_grid": "warning",
      "extra_units": "error",
      "footprint_filter": "ignore",
      "footprint_link_issues": "warning",
      "four_way_junction": "ignore",
      "global_label_dangling": "warning",
      "hier_label_mismatch": "error",
      "label_dangling": "error",
      "label_multiple_wires": "warning",
      "lib_symbol_issues": "warning",
      "lib_symbol_mismatch": "warning",
      "missing_bidi_pin": "warning",
      "missing_input_pin": "warning",
      "missing_power_pin": "error",
      "missing_unit": "warning",
      "multiple_net_names": "warning",
      "net_not_bus_member": "warning",
      "no_connect_connected": "warning",
      "no_connect_dangling": "warning",
      "pin_not_connected": "error",
      "pin_not_driven": "error",
      "pin_to_pin": "error",
      "power_pin_not_driven": "error",
      "same_local_global_label": "warning",
      "similar_label_and_power": "warning",
      "similar_labels": "warning",
      "similar_power": "warning",
      "simulation_model_issue": "ignore",
      "single_global_label": "ignore",
      "unannotated": "error",
      "unconnected_wire_endpoint": "warning",
      "undefined_netclass": "error",
      "unit_value_mismatch": "error",
      "unresolved_variable": "error",
      "wire_dangling": "error"
    }
  },
  "libraries": {
    "pinned_footprint_libs": [],
    "pinned_symbol_libs": []
  },
  "meta": {
    "filename": "cm4-baseboard.kicad_pro",
    "version": 3
  },
  "net_settings": {
    "classes": [
      {
        "bus_width": 12,
        "clearance": 0.125,
        "diff_pair_gap": 0.25,
        "diff_pair_via_gap": 0.25,
        "diff_pair_width": 0.2,
        "line_style": 0,
        "microvia_diameter": 0.3,
        "microvia_drill": 0.1,
        "name": "Default",
        "pcb_color": "rgba(0, 0, 0, 0.000)",
        "priority": 2147483647,
        "schematic_color": "rgba(0, 0, 0, 0.000)",
        "track_width": 0.254,
        "via_diameter": 0.45,
        "via_drill": 0.1,
        "wire_width": 6
      },
      {
        "bus_width": 12,
        "clearance": 0.127,
        "diff_pair_gap": 0.18,
        "diff_pair_width": 0.15,
        "line_style": 0,
        "microvia_diameter": 0.3,
        "microvia_drill": 0.1,
        "name": "100Ohm-diff_CSI",
        "pcb_color": "rgba(0, 0, 0, 0.000)",
        "priority": 0,
        "schematic_color": "rgba(0, 0, 0, 0.000)",
        "track_width": 0.127,
        "via_diameter": 0.45,
        "via_drill": 0.1,
        "wire_width": 6
      },
      {
        "bus_width": 12,
        "clearance": 0.127,
        "diff_pair_gap": 0.18,
        "diff_pair_width": 0.15,
        "line_style": 0,
        "microvia_diameter": 0.3,
        "microvia_drill": 0.1,
        "name": "100Ohm-diff_DSI",
        "pcb_color": "rgba(0, 0, 0, 0.000)",
        "priority": 1,
        "schematic_color": "rgba(0, 0, 0, 0.000)",
        "track_width": 0.127,
        "via_diameter": 0.45,
        "via_drill": 0.1,
        "wire_width": 6
      },
      {
        "bus_width": 12,
        "clearance": 0.127,
        "diff_pair_gap": 0.18,
        "diff_pair_width": 0.15,
        "line_style": 0,
        "microvia_diameter": 0.3,
        "microvia_drill": 0.1,
        "name": "100Ohm-diff_ETH",
        "pcb_color": "rgba(0, 0, 0, 0.000)",
        "priority": 2,
        "schematic_color": "rgba(0, 0, 0, 0.000)",
        "track_width": 0.127,
        "via_diameter": 0.45,
        "via_drill": 0.1,
        "wire_width": 6
      },
      {
        "bus_width": 12,
        "clearance": 0.127,
        "diff_pair_gap": 0.18,
        "diff_pair_width": 0.15,
        "line_style": 0,
        "microvia_diameter": 0.3,
        "microvia_drill": 0.1,
        "name": "100Ohm-diff_HDMI",
        "pcb_color": "rgba(0, 0, 0, 0.000)",
        "priority": 3,
        "schematic_color": "rgba(0, 0, 0, 0.000)",
        "track_width": 0.127,
        "via_diameter": 0.45,
        "via_drill": 0.1,
        "wire_width": 6
      },
      {
        "bus_width": 12,
        "clearance": 0.127,
        "diff_pair_gap": 0.25,
        "diff_pair_width": 0.2,
        "line_style": 0,
        "microvia_diameter": 0.3,
        "microvia_drill": 0.1,
        "name": "50Ohm-se_SDIO",
        "pcb_color": "rgba(0, 0, 0, 0.000)",
        "priority": 4,
        "schematic_color": "rgba(0, 0, 0, 0.000)",
        "track_width": 0.21,
        "via_diameter": 0.45,
        "via_drill": 0.1,
        "wire_width": 6
      },
      {
        "bus_width": 12,
        "clearance": 0.127,
        "diff_pair_gap": 0.15,
        "diff_pair_width": 0.17,
        "line_style": 0,
        "microvia_diameter": 0.3,
        "microvia_drill": 0.1,
        "name": "90Ohm-diff_PCIe2.0",
        "pcb_color": "rgba(0, 0, 0, 0.000)",
        "priority": 5,
        "schematic_color": "rgba(0, 0, 0, 0.000)",
        "track_width": 0.127,
        "via_diameter": 0.5,
        "via_drill": 0.2,
        "wire_width": 6
      },
      {
        "bus_width": 12,
        "clearance": 0.196,
        "diff_pair_gap": 0.196,
        "diff_pair_width": 0.182,
        "line_style": 0,
        "microvia_diameter": 0.3,
        "microvia_drill": 0.1,
        "name": "90Ohm-diff_USB2.0",
        "pcb_color": "rgba(0, 0, 0, 0.000)",
        "priority": 6,
        "schematic_color": "rgba(0, 0, 0, 0.000)",
        "track_width": 0.182,
        "via_diameter": 0.45,
        "via_drill": 0.1,
        "wire_width": 6
      },
      {
        "bus_width": 12,
        "clearance": 0.3,
        "diff_pair_gap": 0.25,
        "diff_pair_width": 0.2,
        "line_style": 0,
        "microvia_diameter": 0.3,
        "microvia_drill": 0.1,
        "name": "PoE",
        "pcb_color": "rgba(0, 0, 0, 0.000)",
        "priority": 7,
        "schematic_color": "rgba(0, 0, 0, 0.000)",
        "track_width": 0.127,
        "via_diameter": 0.45,
        "via_drill": 0.1,
        "wire_width": 6
      }
    ],
    "meta": {
      "version": 4
    },
    "net_colors": null,
    "netclass_assignments": null,
    "netclass_patterns": [
      {
        "netclass": "100Ohm-diff_ETH",
        "pattern": "*ETHERNET.D*"
      },
      {
        "netclass": "90Ohm-diff_USB2.0",
        "pattern": "*USB*D_P"
      },
      {
        "netclass": "90Ohm-diff_USB2.0",
        "pattern": "*USB*D_N"
      },
      {
        "netclass": "100Ohm-diff_CSI",
        "pattern": "*CSI*_P"
      },
      {
        "netclass": "100Ohm-diff_CSI",
        "pattern": "*CSI*_N"
      },
      {
        "netclass": "100Ohm-diff_DSI",
        "pattern": "*DSI.*"
      },
      {
        "netclass": "100Ohm-diff_HDMI",
        "pattern": "*HDMI*_N"
      },
      {
        "netclass": "100Ohm-diff_HDMI",
        "pattern": "*HDMI*_P"
      },
      {
        "netclass": "90Ohm-diff_PCIe2.0",
        "pattern": "*NVMe*_N"
      },
      {
        "netclass": "90Ohm-diff_PCIe2.0",
        "pattern": "*NVMe*_P"
      },
      {
        "netclass": "90Ohm-diff_PCIe2.0",
        "pattern": "/Compute module/??_?"
      },
      {
        "netclass": "50Ohm-se_SDIO",
        "pattern": "*SDIO*"
      },
      {
        "netclass": "PoE",
        "pattern": "/Ethernet/*"
      },
      {
        "netclass": "Default",
        "pattern": "/Ethernet/POE_12V"
      }
    ]
  },
  "pcbnew": {
    "last_paths": {
      "gencad": "",
      "idf": "",
      "netlist": "scalenode-cm4-baseboard.net",
      "plot": "",
      "pos_files": "",
      "specctra_dsn": "",
      "step": "",
      "svg": "",
      "vrml": "scalenode-cm4-baseboard.wrl"
    },
    "page_layout_descr_file": ""
  },
  "schematic": {
    "annotate_start_num": 0,
    "bom_export_filename": "",
    "bom_fmt_presets": [],
    "bom_fmt_settings": {
      "field_delimiter": ",",
      "keep_line_breaks": false,
      "keep_tabs": false,
      "name": "CSV",
      "ref_delimiter": ",",
      "ref_range_delimiter": "",
      "string_delimiter": "\""
    },
    "bom_presets": [],
    "bom_settings": {
      "exclude_dnp": false,
      "fields_ordered": [
        {
          "group_by": false,
          "label": "Reference",
          "name": "Reference",
          "show": true
        },
        {
          "group_by": true,
          "label": "Value",
          "name": "Value",
          "show": true
        },
        {
          "group_by": false,
          "label": "Datasheet",
          "name": "Datasheet",
          "show": true
        },
        {
          "group_by": false,
          "label": "Footprint",
          "name": "Footprint",
          "show": true
        },
        {
          "group_by": false,
          "label": "Qty",
          "name": "${QUANTITY}",
          "show": true
        },
        {
          "group_by": true,
          "label": "DNP",
          "name": "${DNP}",
          "show": true
        }
      ],
      "filter_string": "",
      "group_symbols": true,
      "include_excluded_from_bom": false,
      "name": "Grouped By Value",
      "sort_asc": true,
      "sort_field": "Reference"
    },
    "connection_grid_size": 50.0,
    "drawing": {
      "dashed_lines_dash_length_ratio": 12.0,
      "dashed_lines_gap_length_ratio": 3.0,
      "default_line_thickness": 6.0,
      "default_text_size": 50.0,
      "field_names": [],
      "intersheets_ref_own_page": false,
      "intersheets_ref_prefix": "",
      "intersheets_ref_short": false,
      "intersheets_ref_show": false,
      "intersheets_ref_suffix": "",
      "junction_size_choice": 3,
      "label_size_ratio": 0.25,
      "operating_point_overlay_i_precision": 3,
      "operating_point_overlay_i_range": "~A",
      "operating_point_overlay_v_precision": 3,
      "operating_point_overlay_v_range": "~V",
      "overbar_offset_ratio": 1.23,
      "pin_symbol_size": 0.0,
      "text_offset_ratio": 0.08
    },
    "legacy_lib_dir": "",
    "legacy_lib_list": [],
    "meta": {
      "version": 1
    },
    "net_format_name": "Pcbnew",
    "ngspice": {
      "fix_include_paths": true,
      "fix_passive_vals": false,
      "meta": {
        "version": 0
      },
      "model_mode": 0,
      "workbook_filename": ""
    },
    "page_layout_descr_file": "",
    "plot_directory": "doc/",
    "space_save_all_events": true,
    "spice_adjust_passive_values": false,
    "spice_current_sheet_as_root": false,
    "spice_external_command": "spice \"%I\"",
    "spice_model_current_sheet_as_root": true,
    "spice_save_all_currents": false,
    "spice_save_all_dissipations": false,
    "spice_save_all_voltages": false,
    "subpart_first_id": 65,
    "subpart_id_separator": 0
  },
  "sheets": [
    [
      "",
      "Root"
    ],
    [
      "",
      "Compute module"
    ],
    [
      "",
      "Supply"
    ],
    [
      "",
      "Ethernet"
    ],
    [
      "",
      "NVMe & microSD"
    ],
    [
      "",
      "CSI"
    ],
    [
      "",
      "Display"
    ],
    [
      "",
      "Peripherals"
    ],
    [
      "",
      "USB"
    ]
  ],
  "text_variables": {}
}
